# T6G (Grand Teton) — schematic netlist excerpt (pin names and nets, part order shuffled) for the footprints in the layout excerpt that follows; sources: Cadence DE-HDL packaged netlist, KiCad conversion of 04192023_DAF0TMB3IC0_F0TG_MB_C_brd_V02_OCP.brd

R867  Q_RES  10K 1% CHIP  pkg 0201LF  page 342 : A = RST_RT_CPU1_P2_RESET_R_N ; B = GND
R3610  Q_RES  4.7K 1% EMPTY  pkg 0402LF  page 237 : A = GND ; B = INA230_4_A1
R1370  Q_RES  10K 1% CHIP  pkg 0201LF  page 276 : A = RXDET_BYP_RT_CPU0_P0 ; B = GND

(kicad_pcb
	(version 20260206)
	(generator "pcbnew")
	(generator_version "10.0")
	(general
		(thickness 1.6)
		(legacy_teardrops no)
	)
	(paper "A4")
	(title_block
		(title "04192023_DAF0TMB3IC0_F0TG_MB_C_brd_V02_OCP.brd")
		(comment 1 "Grand Teton / footprints 283-285 of 8354")
	)
	(layers
		(0 "F.Cu" signal "TOP")
		(4 "In1.Cu" signal "GND")
		(6 "In2.Cu" signal "IN1")
		(8 "In3.Cu" signal "GND1")
		(10 "In4.Cu" signal "IN2")
		(12 "In5.Cu" signal "GND2")
		(14 "In6.Cu" signal "IN3")
		(16 "In7.Cu" signal "GND3")
		(18 "In8.Cu" signal "VCC")
		(20 "In9.Cu" signal "VCC1")
		(22 "In10.Cu" signal "GND4")
		(24 "In11.Cu" signal "IN4")
		(26 "In12.Cu" signal "GND5")
		(28 "In13.Cu" signal "IN5")
		(30 "In14.Cu" signal "GND6")
		(32 "In15.Cu" signal "IN6")
		(34 "In16.Cu" signal "GND7")
		(2 "B.Cu" signal "BOTTOM")
		(9 "F.Adhes" user "F.Adhesive")
		(11 "B.Adhes" user "B.Adhesive")
		(13 "F.Paste" user "Package Geometry/Pastemask Top")
		(15 "B.Paste" user "Package Geometry/Pastemask Bottom")
		(5 "F.SilkS" user "Ref Des/Silkscreen Top")
		(7 "B.SilkS" user "Ref Des/Silkscreen Bottom")
		(1 "F.Mask" user "Board Geometry/Soldermask Top")
		(3 "B.Mask" user "Board Geometry/Soldermask Bottom")
		(17 "Dwgs.User" user "User.Drawings")
		(19 "Cmts.User" user "User.Comments")
		(21 "Eco1.User" user "User.Eco1")
		(23 "Eco2.User" user "User.Eco2")
		(25 "Edge.Cuts" user "Board Geometry/Outline")
		(27 "Margin" user)
		(31 "F.CrtYd" user "Package Geometry/Place Bound Top")
		(29 "B.CrtYd" user "Package Geometry/Place Bound Bottom")
		(35 "F.Fab" user "Ref Des/Assembly Top")
		(33 "B.Fab" user "Ref Des/Assembly Bottom")
	)
	(footprint ""
		(layer "F.Cu")
		(at 150.502366 -58.236358)
		(property "Reference" "R3610"
			(at 0 0 0)
			(layer "F.SilkS")
			(hide yes)
			(effects
				(font
					(size 1.27 1.27)
				)
			)
		)
		(property "Value" ""
			(at 0 0 0)
			(layer "F.Fab")
			(effects
				(font
					(size 1.27 1.27)
				)
			)
		)
		(duplicate_pad_numbers_are_jumpers no)
		(fp_line
			(start -0.7874 -0.4064)
			(end 0.7874 -0.4064)
			(stroke
				(width 0.1524)
				(type default)
			)
			(layer "F.SilkS")
		)
		(fp_line
			(start -0.7874 0.4064)
			(end -0.7874 -0.4064)
			(stroke
				(width 0.1524)
				(type default)
			)
			(layer "F.SilkS")
		)
		(fp_line
			(start 0.7874 -0.4064)
			(end 0.7874 0.4064)
			(stroke
				(width 0.1524)
				(type default)
			)
			(layer "F.SilkS")
		)
		(fp_line
			(start 0.7874 0.4064)
			(end -0.7874 0.4064)
			(stroke
				(width 0.1524)
				(type default)
			)
			(layer "F.SilkS")
		)
		(fp_line
			(start -0.67945 -0.305054)
			(end -0.12065 -0.305054)
			(stroke
				(width 0.1)
				(type default)
			)
			(layer "F.Fab")
		)
		(fp_line
			(start -0.67945 0.3048)
			(end -0.67945 -0.305054)
			(stroke
				(width 0.1)
				(type default)
			)
			(layer "F.Fab")
		)
		(fp_line
			(start -0.12065 -0.305054)
			(end -0.12065 -0.2794)
			(stroke
				(width 0.1)
				(type default)
			)
			(layer "F.Fab")
		)
		(fp_line
			(start -0.12065 -0.2794)
			(end 0.12065 -0.2794)
			(stroke
				(width 0.1)
				(type default)
			)
			(layer "F.Fab")
		)
		(fp_line
			(start -0.12065 0.2794)
			(end -0.12065 0.3048)
			(stroke
				(width 0.1)
				(type default)
			)
			(layer "F.Fab")
		)
		(fp_line
			(start -0.12065 0.3048)
			(end -0.67945 0.3048)
			(stroke
				(width 0.1)
				(type default)
			)
			(layer "F.Fab")
		)
		(fp_line
			(start 0.120396 0.2794)
			(end -0.12065 0.2794)
			(stroke
				(width 0.1)
				(type default)
			)
			(layer "F.Fab")
		)
		(fp_line
			(start 0.120396 0.3048)
			(end 0.120396 0.2794)
			(stroke
				(width 0.1)
				(type default)
			)
			(layer "F.Fab")
		)
		(fp_line
			(start 0.12065 -0.3048)
			(end 0.67945 -0.3048)
			(stroke
				(width 0.1)
				(type default)
			)
			(layer "F.Fab")
		)
		(fp_line
			(start 0.12065 -0.2794)
			(end 0.12065 -0.3048)
			(stroke
				(width 0.1)
				(type default)
			)
			(layer "F.Fab")
		)
		(fp_line
			(start 0.67945 -0.3048)
			(end 0.67945 0.3048)
			(stroke
				(width 0.1)
				(type default)
			)
			(layer "F.Fab")
		)
		(fp_line
			(start 0.67945 0.3048)
			(end 0.120396 0.3048)
			(stroke
				(width 0.1)
				(type default)
			)
			(layer "F.Fab")
		)
		(pad "1" smd circle
			(at -0.40005 0)
			(size 0 0)
			(layers "F.Cu" "F.Mask" "F.Paste")
			(net "GND")
		)
		(pad "2" smd circle
			(at 0.40005 0)
			(size 0 0)
			(layers "F.Cu" "F.Mask" "F.Paste")
			(net "INA230_4_A1")
		)
	)
	(footprint ""
		(layer "F.Cu")
		(at 325.697342 -398.34058)
		(property "Reference" "R1370"
			(at 0 0 0)
			(layer "F.SilkS")
			(hide yes)
			(effects
				(font
					(size 1.27 1.27)
				)
			)
		)
		(property "Value" ""
			(at 0 0 0)
			(layer "F.Fab")
			(effects
				(font
					(size 1.27 1.27)
				)
			)
		)
		(duplicate_pad_numbers_are_jumpers no)
		(fp_line
			(start -0.32512 -0.175006)
			(end 0.32512 -0.175006)
			(stroke
				(width 0.1)
				(type default)
			)
			(layer "F.Fab")
		)
		(fp_line
			(start -0.32512 0.175006)
			(end -0.32512 -0.175006)
			(stroke
				(width 0.1)
				(type default)
			)
			(layer "F.Fab")
		)
		(fp_line
			(start 0.32512 -0.175006)
			(end 0.32512 0.175006)
			(stroke
				(width 0.1)
				(type default)
			)
			(layer "F.Fab")
		)
		(fp_line
			(start 0.32512 0.175006)
			(end -0.32512 0.175006)
			(stroke
				(width 0.1)
				(type default)
			)
			(layer "F.Fab")
		)
		(pad "1" smd rect
			(at -0.2667 0)
			(size 0.3048 0.381)
			(layers "F.Cu" "F.Mask" "F.Paste")
			(net "RXDET_BYP_RT_CPU0_P0")
		)
		(pad "2" smd rect
			(at 0.2667 0 180)
			(size 0.3048 0.381)
			(layers "F.Cu" "F.Mask" "F.Paste")
			(net "GND")
		)
	)
	(footprint ""
		(layer "F.Cu")
		(at 144.315688 -394.166852 -90)
		(property "Reference" "R867"
			(at 0 0 270)
			(layer "F.SilkS")
			(hide yes)
			(effects
				(font
					(size 1.27 1.27)
				)
			)
		)
		(property "Value" ""
			(at 0 0 270)
			(layer "F.Fab")
			(effects
				(font
					(size 1.27 1.27)
				)
			)
		)
		(duplicate_pad_numbers_are_jumpers no)
		(fp_line
			(start -0.32512 0.175006)
			(end -0.32512 -0.175006)
			(stroke
				(width 0.1)
				(type default)
			)
			(layer "F.Fab")
		)
		(fp_line
			(start 0.32512 0.175006)
			(end -0.32512 0.175006)
			(stroke
				(width 0.1)
				(type default)
			)
			(layer "F.Fab")
		)
		(fp_line
			(start -0.32512 -0.175006)
			(end 0.32512 -0.175006)
			(stroke
				(width 0.1)
				(type default)
			)
			(layer "F.Fab")
		)
		(fp_line
			(start 0.32512 -0.175006)
			(end 0.32512 0.175006)
			(stroke
				(width 0.1)
				(type default)
			)
			(layer "F.Fab")
		)
		(pad "1" smd rect
			(at -0.2667 0 270)
			(size 0.3048 0.381)
			(layers "F.Cu" "F.Mask" "F.Paste")
			(net "RST_RT_CPU1_P2_RESET_R_N")
		)
		(pad "2" smd rect
			(at 0.2667 0 90)
			(size 0.3048 0.381)
			(layers "F.Cu" "F.Mask" "F.Paste")
			(net "GND")
		)
	)
)
